(kicad_pcb
	(version 20260206)
	(generator "pcbnew")
	(generator_version "10.0")
	(general
		(thickness 1.6)
		(legacy_teardrops no)
	)
	(paper "A4")
	(title_block
		(title "04192023_DAF0TMB3IC0_F0TG_MB_C_brd_V02_OCP.brd")
		(comment 1 "Grand Teton / footprints 1828-1834 of 8354")
	)
	(layers
		(0 "F.Cu" signal "TOP")
		(4 "In1.Cu" signal "GND")
		(6 "In2.Cu" signal "IN1")
		(8 "In3.Cu" signal "GND1")
		(10 "In4.Cu" signal "IN2")
		(12 "In5.Cu" signal "GND2")
		(14 "In6.Cu" signal "IN3")
		(16 "In7.Cu" signal "GND3")
		(18 "In8.Cu" signal "VCC")
		(20 "In9.Cu" signal "VCC1")
		(22 "In10.Cu" signal "GND4")
		(24 "In11.Cu" signal "IN4")
		(26 "In12.Cu" signal "GND5")
		(28 "In13.Cu" signal "IN5")
		(30 "In14.Cu" signal "GND6")
		(32 "In15.Cu" signal "IN6")
		(34 "In16.Cu" signal "GND7")
		(2 "B.Cu" signal "BOTTOM")
		(9 "F.Adhes" user "F.Adhesive")
		(11 "B.Adhes" user "B.Adhesive")
		(13 "F.Paste" user "Package Geometry/Pastemask Top")
		(15 "B.Paste" user "Package Geometry/Pastemask Bottom")
		(5 "F.SilkS" user "Ref Des/Silkscreen Top")
		(7 "B.SilkS" user "Ref Des/Silkscreen Bottom")
		(1 "F.Mask" user "Board Geometry/Soldermask Top")
		(3 "B.Mask" user "Board Geometry/Soldermask Bottom")
		(17 "Dwgs.User" user "User.Drawings")
		(19 "Cmts.User" user "User.Comments")
		(21 "Eco1.User" user "User.Eco1")
		(23 "Eco2.User" user "User.Eco2")
		(25 "Edge.Cuts" user "Board Geometry/Outline")
		(27 "Margin" user)
		(31 "F.CrtYd" user "Package Geometry/Place Bound Top")
		(29 "B.CrtYd" user "Package Geometry/Place Bound Bottom")
		(35 "F.Fab" user "Ref Des/Assembly Top")
		(33 "B.Fab" user "Ref Des/Assembly Bottom")
	)
	(footprint ""
		(layer "F.Cu")
		(at 104.267 -416.814 180)
		(property "Reference" "R579"
			(at 0 0 180)
			(layer "F.SilkS")
			(hide yes)
			(effects
				(font
					(size 1.27 1.27)
				)
			)
		)
		(property "Value" ""
			(at 0 0 180)
			(layer "F.Fab")
			(effects
				(font
					(size 1.27 1.27)
				)
			)
		)
		(duplicate_pad_numbers_are_jumpers no)
		(fp_line
			(start 0.7874 0.4064)
			(end -0.7874 0.4064)
			(stroke
				(width 0.1524)
				(type default)
			)
			(layer "F.SilkS")
		)
		(fp_line
			(start 0.7874 -0.4064)
			(end 0.7874 0.4064)
			(stroke
				(width 0.1524)
				(type default)
			)
			(layer "F.SilkS")
		)
		(fp_line
			(start -0.7874 0.4064)
			(end -0.7874 -0.4064)
			(stroke
				(width 0.1524)
				(type default)
			)
			(layer "F.SilkS")
		)
		(fp_line
			(start -0.7874 -0.4064)
			(end 0.7874 -0.4064)
			(stroke
				(width 0.1524)
				(type default)
			)
			(layer "F.SilkS")
		)
		(fp_line
			(start 0.67945 0.3048)
			(end 0.120396 0.3048)
			(stroke
				(width 0.1)
				(type default)
			)
			(layer "F.Fab")
		)
		(fp_line
			(start 0.67945 -0.3048)
			(end 0.67945 0.3048)
			(stroke
				(width 0.1)
				(type default)
			)
			(layer "F.Fab")
		)
		(fp_line
			(start 0.12065 -0.2794)
			(end 0.12065 -0.3048)
			(stroke
				(width 0.1)
				(type default)
			)
			(layer "F.Fab")
		)
		(fp_line
			(start 0.12065 -0.3048)
			(end 0.67945 -0.3048)
			(stroke
				(width 0.1)
				(type default)
			)
			(layer "F.Fab")
		)
		(fp_line
			(start 0.120396 0.3048)
			(end 0.120396 0.2794)
			(stroke
				(width 0.1)
				(type default)
			)
			(layer "F.Fab")
		)
		(fp_line
			(start 0.120396 0.2794)
			(end -0.12065 0.2794)
			(stroke
				(width 0.1)
				(type default)
			)
			(layer "F.Fab")
		)
		(fp_line
			(start -0.12065 0.3048)
			(end -0.67945 0.3048)
			(stroke
				(width 0.1)
				(type default)
			)
			(layer "F.Fab")
		)
		(fp_line
			(start -0.12065 0.2794)
			(end -0.12065 0.3048)
			(stroke
				(width 0.1)
				(type default)
			)
			(layer "F.Fab")
		)
		(fp_line
			(start -0.12065 -0.2794)
			(end 0.12065 -0.2794)
			(stroke
				(width 0.1)
				(type default)
			)
			(layer "F.Fab")
		)
		(fp_line
			(start -0.12065 -0.305054)
			(end -0.12065 -0.2794)
			(stroke
				(width 0.1)
				(type default)
			)
			(layer "F.Fab")
		)
		(fp_line
			(start -0.67945 0.3048)
			(end -0.67945 -0.305054)
			(stroke
				(width 0.1)
				(type default)
			)
			(layer "F.Fab")
		)
		(fp_line
			(start -0.67945 -0.305054)
			(end -0.12065 -0.305054)
			(stroke
				(width 0.1)
				(type default)
			)
			(layer "F.Fab")
		)
		(pad "1" smd circle
			(at -0.40005 0 180)
			(size 0 0)
			(layers "F.Cu" "F.Mask" "F.Paste")
			(net "CLK_9ZXL045_P1_SADR0")
		)
		(pad "2" smd circle
			(at 0.40005 0 180)
			(size 0 0)
			(layers "F.Cu" "F.Mask" "F.Paste")
			(net "GND")
		)
	)
	(footprint ""
		(layer "F.Cu")
		(at 26.793444 -423.509694 180)
		(property "Reference" "R3278"
			(at 0 0 180)
			(layer "F.SilkS")
			(hide yes)
			(effects
				(font
					(size 1.27 1.27)
				)
			)
		)
		(property "Value" ""
			(at 0 0 180)
			(layer "F.Fab")
			(effects
				(font
					(size 1.27 1.27)
				)
			)
		)
		(duplicate_pad_numbers_are_jumpers no)
		(fp_line
			(start 0.7874 0.4064)
			(end -0.7874 0.4064)
			(stroke
				(width 0.1524)
				(type default)
			)
			(layer "F.SilkS")
		)
		(fp_line
			(start 0.7874 -0.4064)
			(end 0.7874 0.4064)
			(stroke
				(width 0.1524)
				(type default)
			)
			(layer "F.SilkS")
		)
		(fp_line
			(start -0.7874 0.4064)
			(end -0.7874 -0.4064)
			(stroke
				(width 0.1524)
				(type default)
			)
			(layer "F.SilkS")
		)
		(fp_line
			(start -0.7874 -0.4064)
			(end 0.7874 -0.4064)
			(stroke
				(width 0.1524)
				(type default)
			)
			(layer "F.SilkS")
		)
		(fp_line
			(start 0.67945 0.3048)
			(end 0.120396 0.3048)
			(stroke
				(width 0.1)
				(type default)
			)
			(layer "F.Fab")
		)
		(fp_line
			(start 0.67945 -0.3048)
			(end 0.67945 0.3048)
			(stroke
				(width 0.1)
				(type default)
			)
			(layer "F.Fab")
		)
		(fp_line
			(start 0.12065 -0.2794)
			(end 0.12065 -0.3048)
			(stroke
				(width 0.1)
				(type default)
			)
			(layer "F.Fab")
		)
		(fp_line
			(start 0.12065 -0.3048)
			(end 0.67945 -0.3048)
			(stroke
				(width 0.1)
				(type default)
			)
			(layer "F.Fab")
		)
		(fp_line
			(start 0.120396 0.3048)
			(end 0.120396 0.2794)
			(stroke
				(width 0.1)
				(type default)
			)
			(layer "F.Fab")
		)
		(fp_line
			(start 0.120396 0.2794)
			(end -0.12065 0.2794)
			(stroke
				(width 0.1)
				(type default)
			)
			(layer "F.Fab")
		)
		(fp_line
			(start -0.12065 0.3048)
			(end -0.67945 0.3048)
			(stroke
				(width 0.1)
				(type default)
			)
			(layer "F.Fab")
		)
		(fp_line
			(start -0.12065 0.2794)
			(end -0.12065 0.3048)
			(stroke
				(width 0.1)
				(type default)
			)
			(layer "F.Fab")
		)
		(fp_line
			(start -0.12065 -0.2794)
			(end 0.12065 -0.2794)
			(stroke
				(width 0.1)
				(type default)
			)
			(layer "F.Fab")
		)
		(fp_line
			(start -0.12065 -0.305054)
			(end -0.12065 -0.2794)
			(stroke
				(width 0.1)
				(type default)
			)
			(layer "F.Fab")
		)
		(fp_line
			(start -0.67945 0.3048)
			(end -0.67945 -0.305054)
			(stroke
				(width 0.1)
				(type default)
			)
			(layer "F.Fab")
		)
		(fp_line
			(start -0.67945 -0.305054)
			(end -0.12065 -0.305054)
			(stroke
				(width 0.1)
				(type default)
			)
			(layer "F.Fab")
		)
		(pad "1" smd circle
			(at -0.40005 0 180)
			(size 0 0)
			(layers "F.Cu" "F.Mask" "F.Paste")
			(net "FM_P2E_EQA0")
		)
		(pad "2" smd circle
			(at 0.40005 0 180)
			(size 0 0)
			(layers "F.Cu" "F.Mask" "F.Paste")
			(net "GND")
		)
	)
	(footprint ""
		(layer "F.Cu")
		(at 75.49515 -375.94286 180)
		(property "Reference" "C739"
			(at 0 0 180)
			(layer "F.SilkS")
			(hide yes)
			(effects
				(font
					(size 1.27 1.27)
				)
			)
		)
		(property "Value" ""
			(at 0 0 180)
			(layer "F.Fab")
			(effects
				(font
					(size 1.27 1.27)
				)
			)
		)
		(duplicate_pad_numbers_are_jumpers no)
		(fp_line
			(start 0.299974 0.150114)
			(end -0.299974 0.150114)
			(stroke
				(width 0.1)
				(type default)
			)
			(layer "F.Fab")
		)
		(fp_line
			(start 0.299974 -0.150114)
			(end 0.299974 0.150114)
			(stroke
				(width 0.1)
				(type default)
			)
			(layer "F.Fab")
		)
		(fp_line
			(start -0.299974 0.150114)
			(end -0.299974 -0.150114)
			(stroke
				(width 0.1)
				(type default)
			)
			(layer "F.Fab")
		)
		(fp_line
			(start -0.299974 -0.150114)
			(end 0.299974 -0.150114)
			(stroke
				(width 0.1)
				(type default)
			)
			(layer "F.Fab")
		)
		(pad "1" smd rect
			(at -0.2667 0 180)
			(size 0.3048 0.381)
			(layers "F.Cu" "F.Mask" "F.Paste")
			(net "P5E_CPU1_P1_TX_C_DP<1>")
		)
		(pad "2" smd rect
			(at 0.2667 0 180)
			(size 0.3048 0.381)
			(layers "F.Cu" "F.Mask" "F.Paste")
			(net "P5E_CPU1_P1_TX_DP<1>")
		)
	)
	(footprint ""
		(layer "F.Cu")
		(at 357.338122 -164.284406)
		(property "Reference" "PR353"
			(at 0 0 0)
			(layer "F.SilkS")
			(hide yes)
			(effects
				(font
					(size 1.27 1.27)
				)
			)
		)
		(property "Value" ""
			(at 0 0 0)
			(layer "F.Fab")
			(effects
				(font
					(size 1.27 1.27)
				)
			)
		)
		(duplicate_pad_numbers_are_jumpers no)
		(fp_line
			(start -0.7874 -0.4064)
			(end 0.7874 -0.4064)
			(stroke
				(width 0.1524)
				(type default)
			)
			(layer "F.SilkS")
		)
		(fp_line
			(start -0.7874 0.4064)
			(end -0.7874 -0.4064)
			(stroke
				(width 0.1524)
				(type default)
			)
			(layer "F.SilkS")
		)
		(fp_line
			(start 0.7874 -0.4064)
			(end 0.7874 0.4064)
			(stroke
				(width 0.1524)
				(type default)
			)
			(layer "F.SilkS")
		)
		(fp_line
			(start 0.7874 0.4064)
			(end -0.7874 0.4064)
			(stroke
				(width 0.1524)
				(type default)
			)
			(layer "F.SilkS")
		)
		(fp_line
			(start -0.67945 -0.305054)
			(end -0.12065 -0.305054)
			(stroke
				(width 0.1)
				(type default)
			)
			(layer "F.Fab")
		)
		(fp_line
			(start -0.67945 0.3048)
			(end -0.67945 -0.305054)
			(stroke
				(width 0.1)
				(type default)
			)
			(layer "F.Fab")
		)
		(fp_line
			(start -0.12065 -0.305054)
			(end -0.12065 -0.2794)
			(stroke
				(width 0.1)
				(type default)
			)
			(layer "F.Fab")
		)
		(fp_line
			(start -0.12065 -0.2794)
			(end 0.12065 -0.2794)
			(stroke
				(width 0.1)
				(type default)
			)
			(layer "F.Fab")
		)
		(fp_line
			(start -0.12065 0.2794)
			(end -0.12065 0.3048)
			(stroke
				(width 0.1)
				(type default)
			)
			(layer "F.Fab")
		)
		(fp_line
			(start -0.12065 0.3048)
			(end -0.67945 0.3048)
			(stroke
				(width 0.1)
				(type default)
			)
			(layer "F.Fab")
		)
		(fp_line
			(start 0.120396 0.2794)
			(end -0.12065 0.2794)
			(stroke
				(width 0.1)
				(type default)
			)
			(layer "F.Fab")
		)
		(fp_line
			(start 0.120396 0.3048)
			(end 0.120396 0.2794)
			(stroke
				(width 0.1)
				(type default)
			)
			(layer "F.Fab")
		)
		(fp_line
			(start 0.12065 -0.3048)
			(end 0.67945 -0.3048)
			(stroke
				(width 0.1)
				(type default)
			)
			(layer "F.Fab")
		)
		(fp_line
			(start 0.12065 -0.2794)
			(end 0.12065 -0.3048)
			(stroke
				(width 0.1)
				(type default)
			)
			(layer "F.Fab")
		)
		(fp_line
			(start 0.67945 -0.3048)
			(end 0.67945 0.3048)
			(stroke
				(width 0.1)
				(type default)
			)
			(layer "F.Fab")
		)
		(fp_line
			(start 0.67945 0.3048)
			(end 0.120396 0.3048)
			(stroke
				(width 0.1)
				(type default)
			)
			(layer "F.Fab")
		)
		(pad "1" smd circle
			(at -0.40005 0)
			(size 0 0)
			(layers "F.Cu" "F.Mask" "F.Paste")
			(net "GND")
		)
		(pad "2" smd circle
			(at 0.40005 0)
			(size 0 0)
			(layers "F.Cu" "F.Mask" "F.Paste")
			(net "PVDDCR_CPU0_P0_LSET5")
		)
	)
	(footprint ""
		(layer "F.Cu")
		(at 163.703 -110.200948 180)
		(property "Reference" "R1195"
			(at 0 0 180)
			(layer "F.SilkS")
			(hide yes)
			(effects
				(font
					(size 1.27 1.27)
				)
			)
		)
		(property "Value" ""
			(at 0 0 180)
			(layer "F.Fab")
			(effects
				(font
					(size 1.27 1.27)
				)
			)
		)
		(duplicate_pad_numbers_are_jumpers no)
		(fp_line
			(start 0.7874 0.4064)
			(end -0.7874 0.4064)
			(stroke
				(width 0.1524)
				(type default)
			)
			(layer "F.SilkS")
		)
		(fp_line
			(start 0.7874 -0.4064)
			(end 0.7874 0.4064)
			(stroke
				(width 0.1524)
				(type default)
			)
			(layer "F.SilkS")
		)
		(fp_line
			(start -0.7874 0.4064)
			(end -0.7874 -0.4064)
			(stroke
				(width 0.1524)
				(type default)
			)
			(layer "F.SilkS")
		)
		(fp_line
			(start -0.7874 -0.4064)
			(end 0.7874 -0.4064)
			(stroke
				(width 0.1524)
				(type default)
			)
			(layer "F.SilkS")
		)
		(fp_line
			(start 0.67945 0.3048)
			(end 0.120396 0.3048)
			(stroke
				(width 0.1)
				(type default)
			)
			(layer "F.Fab")
		)
		(fp_line
			(start 0.67945 -0.3048)
			(end 0.67945 0.3048)
			(stroke
				(width 0.1)
				(type default)
			)
			(layer "F.Fab")
		)
		(fp_line
			(start 0.12065 -0.2794)
			(end 0.12065 -0.3048)
			(stroke
				(width 0.1)
				(type default)
			)
			(layer "F.Fab")
		)
		(fp_line
			(start 0.12065 -0.3048)
			(end 0.67945 -0.3048)
			(stroke
				(width 0.1)
				(type default)
			)
			(layer "F.Fab")
		)
		(fp_line
			(start 0.120396 0.3048)
			(end 0.120396 0.2794)
			(stroke
				(width 0.1)
				(type default)
			)
			(layer "F.Fab")
		)
		(fp_line
			(start 0.120396 0.2794)
			(end -0.12065 0.2794)
			(stroke
				(width 0.1)
				(type default)
			)
			(layer "F.Fab")
		)
		(fp_line
			(start -0.12065 0.3048)
			(end -0.67945 0.3048)
			(stroke
				(width 0.1)
				(type default)
			)
			(layer "F.Fab")
		)
		(fp_line
			(start -0.12065 0.2794)
			(end -0.12065 0.3048)
			(stroke
				(width 0.1)
				(type default)
			)
			(layer "F.Fab")
		)
		(fp_line
			(start -0.12065 -0.2794)
			(end 0.12065 -0.2794)
			(stroke
				(width 0.1)
				(type default)
			)
			(layer "F.Fab")
		)
		(fp_line
			(start -0.12065 -0.305054)
			(end -0.12065 -0.2794)
			(stroke
				(width 0.1)
				(type default)
			)
			(layer "F.Fab")
		)
		(fp_line
			(start -0.67945 0.3048)
			(end -0.67945 -0.305054)
			(stroke
				(width 0.1)
				(type default)
			)
			(layer "F.Fab")
		)
		(fp_line
			(start -0.67945 -0.305054)
			(end -0.12065 -0.305054)
			(stroke
				(width 0.1)
				(type default)
			)
			(layer "F.Fab")
		)
		(pad "1" smd circle
			(at -0.40005 0 180)
			(size 0 0)
			(layers "F.Cu" "F.Mask" "F.Paste")
			(net "P12V_OCP_SFF_EN_R")
		)
		(pad "2" smd circle
			(at 0.40005 0 180)
			(size 0 0)
			(layers "F.Cu" "F.Mask" "F.Paste")
			(net "P3V3_AUX")
		)
	)
	(footprint ""
		(layer "F.Cu")
		(at 307.746146 -416.899344 -90)
		(property "Reference" "C6503"
			(at 0 0 270)
			(layer "F.SilkS")
			(hide yes)
			(effects
				(font
					(size 1.27 1.27)
				)
			)
		)
		(property "Value" ""
			(at 0 0 270)
			(layer "F.Fab")
			(effects
				(font
					(size 1.27 1.27)
				)
			)
		)
		(duplicate_pad_numbers_are_jumpers no)
		(fp_line
			(start -0.299974 0.150114)
			(end -0.299974 -0.150114)
			(stroke
				(width 0.1)
				(type default)
			)
			(layer "F.Fab")
		)
		(fp_line
			(start 0.299974 0.150114)
			(end -0.299974 0.150114)
			(stroke
				(width 0.1)
				(type default)
			)
			(layer "F.Fab")
		)
		(fp_line
			(start -0.299974 -0.150114)
			(end 0.299974 -0.150114)
			(stroke
				(width 0.1)
				(type default)
			)
			(layer "F.Fab")
		)
		(fp_line
			(start 0.299974 -0.150114)
			(end 0.299974 0.150114)
			(stroke
				(width 0.1)
				(type default)
			)
			(layer "F.Fab")
		)
		(pad "1" smd rect
			(at -0.2667 0 270)
			(size 0.3048 0.381)
			(layers "F.Cu" "F.Mask" "F.Paste")
			(net "P5E_CPU0_P0_TX_BUF_C_DP<1>")
		)
		(pad "2" smd rect
			(at 0.2667 0 270)
			(size 0.3048 0.381)
			(layers "F.Cu" "F.Mask" "F.Paste")
			(net "P5E_CPU0_P0_TX_BUF_DP<1>")
		)
	)
	(footprint ""
		(layer "F.Cu")
		(at 455.01306 -38.565836)
		(property "Reference" "R45"
			(at 0 0 0)
			(layer "F.SilkS")
			(hide yes)
			(effects
				(font
					(size 1.27 1.27)
				)
			)
		)
		(property "Value" ""
			(at 0 0 0)
			(layer "F.Fab")
			(effects
				(font
					(size 1.27 1.27)
				)
			)
		)
		(duplicate_pad_numbers_are_jumpers no)
		(fp_line
			(start -0.7874 -0.4064)
			(end 0.7874 -0.4064)
			(stroke
				(width 0.1524)
				(type default)
			)
			(layer "F.SilkS")
		)
		(fp_line
			(start -0.7874 0.4064)
			(end -0.7874 -0.4064)
			(stroke
				(width 0.1524)
				(type default)
			)
			(layer "F.SilkS")
		)
		(fp_line
			(start 0.7874 -0.4064)
			(end 0.7874 0.4064)
			(stroke
				(width 0.1524)
				(type default)
			)
			(layer "F.SilkS")
		)
		(fp_line
			(start 0.7874 0.4064)
			(end -0.7874 0.4064)
			(stroke
				(width 0.1524)
				(type default)
			)
			(layer "F.SilkS")
		)
		(fp_line
			(start -0.67945 -0.305054)
			(end -0.12065 -0.305054)
			(stroke
				(width 0.1)
				(type default)
			)
			(layer "F.Fab")
		)
		(fp_line
			(start -0.67945 0.3048)
			(end -0.67945 -0.305054)
			(stroke
				(width 0.1)
				(type default)
			)
			(layer "F.Fab")
		)
		(fp_line
			(start -0.12065 -0.305054)
			(end -0.12065 -0.2794)
			(stroke
				(width 0.1)
				(type default)
			)
			(layer "F.Fab")
		)
		(fp_line
			(start -0.12065 -0.2794)
			(end 0.12065 -0.2794)
			(stroke
				(width 0.1)
				(type default)
			)
			(layer "F.Fab")
		)
		(fp_line
			(start -0.12065 0.2794)
			(end -0.12065 0.3048)
			(stroke
				(width 0.1)
				(type default)
			)
			(layer "F.Fab")
		)
		(fp_line
			(start -0.12065 0.3048)
			(end -0.67945 0.3048)
			(stroke
				(width 0.1)
				(type default)
			)
			(layer "F.Fab")
		)
		(fp_line
			(start 0.120396 0.2794)
			(end -0.12065 0.2794)
			(stroke
				(width 0.1)
				(type default)
			)
			(layer "F.Fab")
		)
		(fp_line
			(start 0.120396 0.3048)
			(end 0.120396 0.2794)
			(stroke
				(width 0.1)
				(type default)
			)
			(layer "F.Fab")
		)
		(fp_line
			(start 0.12065 -0.3048)
			(end 0.67945 -0.3048)
			(stroke
				(width 0.1)
				(type default)
			)
			(layer "F.Fab")
		)
		(fp_line
			(start 0.12065 -0.2794)
			(end 0.12065 -0.3048)
			(stroke
				(width 0.1)
				(type default)
			)
			(layer "F.Fab")
		)
		(fp_line
			(start 0.67945 -0.3048)
			(end 0.67945 0.3048)
			(stroke
				(width 0.1)
				(type default)
			)
			(layer "F.Fab")
		)
		(fp_line
			(start 0.67945 0.3048)
			(end 0.120396 0.3048)
			(stroke
				(width 0.1)
				(type default)
			)
			(layer "F.Fab")
		)
		(pad "1" smd circle
			(at -0.40005 0)
			(size 0 0)
			(layers "F.Cu" "F.Mask" "F.Paste")
			(net "P3V3_OCP_SFF")
		)
		(pad "2" smd circle
			(at 0.40005 0)
			(size 0 0)
			(layers "F.Cu" "F.Mask" "F.Paste")
			(net "PU_OCP_SFF_WAKE_OE")
		)
	)
)
